(kicad_pcb
	(version 20260206)
	(generator "pcbnew")
	(generator_version "10.0")
	(general
		(thickness 1.6)
		(legacy_teardrops no)
	)
	(paper "A4")
	(title_block
		(title "03242023_DA0F0TMBIJ0_F0T_Motherboard_J_brd_V01_OCP.brd")
		(comment 1 "Grand Teton / footprint 1682 of 6105 (U1), pads 427-533 of 4677")
	)
	(layers
		(0 "F.Cu" signal "TOP")
		(4 "In1.Cu" signal "GND")
		(6 "In2.Cu" signal "IN1")
		(8 "In3.Cu" signal "GND1")
		(10 "In4.Cu" signal "IN2")
		(12 "In5.Cu" signal "GND2")
		(14 "In6.Cu" signal "IN3")
		(16 "In7.Cu" signal "GND3")
		(18 "In8.Cu" signal "VCC")
		(20 "In9.Cu" signal "VCC1")
		(22 "In10.Cu" signal "GND4")
		(24 "In11.Cu" signal "IN4")
		(26 "In12.Cu" signal "GND5")
		(28 "In13.Cu" signal "IN5")
		(30 "In14.Cu" signal "GND6")
		(32 "In15.Cu" signal "IN6")
		(34 "In16.Cu" signal "GND7")
		(2 "B.Cu" signal "BOTTOM")
		(9 "F.Adhes" user "F.Adhesive")
		(11 "B.Adhes" user "B.Adhesive")
		(13 "F.Paste" user "Package Geometry/Pastemask Top")
		(15 "B.Paste" user "Package Geometry/Pastemask Bottom")
		(5 "F.SilkS" user "Ref Des/Silkscreen Top")
		(7 "B.SilkS" user "Ref Des/Silkscreen Bottom")
		(1 "F.Mask" user "Board Geometry/Soldermask Top")
		(3 "B.Mask" user "Board Geometry/Soldermask Bottom")
		(17 "Dwgs.User" user "User.Drawings")
		(19 "Cmts.User" user "User.Comments")
		(21 "Eco1.User" user "User.Eco1")
		(23 "Eco2.User" user "User.Eco2")
		(25 "Edge.Cuts" user "Board Geometry/Outline")
		(27 "Margin" user)
		(31 "F.CrtYd" user "Package Geometry/Place Bound Top")
		(29 "B.CrtYd" user "Package Geometry/Place Bound Bottom")
		(35 "F.Fab" user "Ref Des/Assembly Top")
		(33 "B.Fab" user "Ref Des/Assembly Bottom")
	)
	(footprint ""
		(layer "F.Cu")
		(at 111.93018 -251.76988 90)
		(property "Reference" "U1"
			(at -74.913236 41.548812 0)
			(unlocked yes)
			(layer "F.SilkS")
			(effects
				(font
					(size 1.6002 1.1938)
					(thickness 0.1524)
				)
				(justify left)
			)
		)
		(property "Value" ""
			(at 0 0 90)
			(layer "F.Fab")
			(effects
				(font
					(size 1.27 1.27)
				)
			)
		)
		(duplicate_pad_numbers_are_jumpers no)
		(pad "AJ82" smd circle
			(at 30.100016 -13.806932 270)
			(size 0.4318 0.4318)
			(layers "F.Cu" "F.Mask" "F.Paste")
			(net "UPI_CPU0_CPU1_P2P2_DP<11>")
		)
		(pad "AJ84" smd circle
			(at 31.727902 -13.806932 270)
			(size 0.4318 0.4318)
			(layers "F.Cu" "F.Mask" "F.Paste")
			(net "GND")
		)
		(pad "AJ86" smd circle
			(at 33.355534 -13.806932 270)
			(size 0.4318 0.4318)
			(layers "F.Cu" "F.Mask" "F.Paste")
			(net "P5E_CPU1_PE4_TX_DN<9>")
		)
		(pad "AJ88" smd circle
			(at 34.98342 -13.806932 270)
			(size 0.4318 0.4318)
			(layers "F.Cu" "F.Mask" "F.Paste")
			(net "GND")
		)
		(pad "AJ90" smd circle
			(at 36.611306 -13.806932 270)
			(size 0.4318 0.4318)
			(layers "F.Cu" "F.Mask" "F.Paste")
			(net "P5E_CPU1_PE4_RX_DP<9>")
		)
		(pad "AK2" smd circle
			(at -36.611306 -13.447268 270)
			(size 0.4318 0.4318)
			(layers "F.Cu" "F.Mask" "F.Paste")
			(net "UPI_CPU1_CPU0_P0P1_DN<10>")
		)
		(pad "AK4" smd circle
			(at -34.98342 -13.447268 270)
			(size 0.4318 0.4318)
			(layers "F.Cu" "F.Mask" "F.Paste")
			(net "GND")
		)
		(pad "AK6" smd circle
			(at -33.355534 -13.447268 270)
			(size 0.4318 0.4318)
			(layers "F.Cu" "F.Mask" "F.Paste")
			(net "UPI_CPU0_CPU1_P1P0_DN<10>")
		)
		(pad "AK8" smd circle
			(at -31.727902 -13.447268 270)
			(size 0.4318 0.4318)
			(layers "F.Cu" "F.Mask" "F.Paste")
			(net "GND")
		)
		(pad "AK10" smd circle
			(at -30.100016 -13.447268 270)
			(size 0.4318 0.4318)
			(layers "F.Cu" "F.Mask" "F.Paste")
			(net "P5E_CPU1_PE0_RX_DN<10>")
		)
		(pad "AK12" smd circle
			(at -28.472384 -13.447268 270)
			(size 0.4318 0.4318)
			(layers "F.Cu" "F.Mask" "F.Paste")
			(net "GND")
		)
		(pad "AK14" smd circle
			(at -26.844498 -13.447268 270)
			(size 0.4318 0.4318)
			(layers "F.Cu" "F.Mask" "F.Paste")
			(net "P5E_CPU1_PE0_TX_DN<9>")
		)
		(pad "AK16" smd circle
			(at -25.216612 -13.447268 270)
			(size 0.4318 0.4318)
			(layers "F.Cu" "F.Mask" "F.Paste")
			(net "GND")
		)
		(pad "AK18" smd circle
			(at -23.58898 -13.447268 270)
			(size 0.4318 0.4318)
			(layers "F.Cu" "F.Mask" "F.Paste")
			(net "GND")
		)
		(pad "AK20" smd circle
			(at -21.961094 -13.447268 270)
			(size 0.4318 0.4318)
			(layers "F.Cu" "F.Mask" "F.Paste")
			(net "M_D_CPU1_SB_DQ<28>")
		)
		(pad "AK22" smd circle
			(at -20.333462 -13.447268 270)
			(size 0.4318 0.4318)
			(layers "F.Cu" "F.Mask" "F.Paste")
			(net "M_D_CPU1_SB_DQ<25>")
		)
		(pad "AK24" smd circle
			(at -18.705576 -13.447268 270)
			(size 0.4318 0.4318)
			(layers "F.Cu" "F.Mask" "F.Paste")
			(net "GND")
		)
		(pad "AK26" smd circle
			(at -17.07769 -13.447268 270)
			(size 0.4318 0.4318)
			(layers "F.Cu" "F.Mask" "F.Paste")
			(net "M_D_CPU1_SB_DQ<12>")
		)
		(pad "AK28" smd circle
			(at -15.450058 -13.447268 270)
			(size 0.4318 0.4318)
			(layers "F.Cu" "F.Mask" "F.Paste")
			(net "M_D_CPU1_SB_DQ<9>")
		)
		(pad "AK30" smd circle
			(at -13.822426 -13.447268 270)
			(size 0.4318 0.4318)
			(layers "F.Cu" "F.Mask" "F.Paste")
			(net "GND")
		)
		(pad "AK32" smd circle
			(at -12.19454 -13.447268 270)
			(size 0.4318 0.4318)
			(layers "F.Cu" "F.Mask" "F.Paste")
			(net "M_D_CPU1_SB_DQ<4>")
		)
		(pad "AK34" smd circle
			(at -10.566654 -13.447268 270)
			(size 0.4318 0.4318)
			(layers "F.Cu" "F.Mask" "F.Paste")
			(net "M_D_CPU1_SB_DQ<1>")
		)
		(pad "AK36" smd circle
			(at -8.939022 -13.447268 270)
			(size 0.4318 0.4318)
			(layers "F.Cu" "F.Mask" "F.Paste")
			(net "GND")
		)
		(pad "AK38" smd circle
			(at -7.311136 -13.447268 270)
			(size 0.4318 0.4318)
			(layers "F.Cu" "F.Mask" "F.Paste")
			(net "M_D_CPU1_SB_CB<0>")
		)
		(pad "AK40" smd circle
			(at -5.68325 -13.447268 270)
			(size 0.4318 0.4318)
			(layers "F.Cu" "F.Mask" "F.Paste")
			(net "M_D_CPU1_SB_CB<5>")
		)
		(pad "AK42" smd circle
			(at -4.055618 -13.447268 270)
			(size 0.4318 0.4318)
			(layers "F.Cu" "F.Mask" "F.Paste")
			(net "GND")
		)
		(pad "AK44" smd circle
			(at -2.427732 -13.447268 270)
			(size 0.4318 0.4318)
			(layers "F.Cu" "F.Mask" "F.Paste")
			(net "M_D_CPU1_SB_CA<0>")
		)
		(pad "AK47" smd circle
			(at 1.613916 -13.337286 270)
			(size 0.4318 0.4318)
			(layers "F.Cu" "F.Mask" "F.Paste")
			(net "M_B_CPU1_SA_RSP<1>")
		)
		(pad "AK49" smd circle
			(at 3.241802 -13.337286 270)
			(size 0.4318 0.4318)
			(layers "F.Cu" "F.Mask" "F.Paste")
			(net "GND")
		)
		(pad "AK51" smd circle
			(at 4.869434 -13.337286 270)
			(size 0.4318 0.4318)
			(layers "F.Cu" "F.Mask" "F.Paste")
			(net "M_D_CPU1_SA_CA<2>")
		)
		(pad "AK53" smd circle
			(at 6.49732 -13.337286 270)
			(size 0.4318 0.4318)
			(layers "F.Cu" "F.Mask" "F.Paste")
			(net "M_D_CPU1_SA_CS_N<1>")
		)
		(pad "AK55" smd circle
			(at 8.124952 -13.337286 270)
			(size 0.4318 0.4318)
			(layers "F.Cu" "F.Mask" "F.Paste")
			(net "GND")
		)
		(pad "AK57" smd circle
			(at 9.752838 -13.337286 270)
			(size 0.4318 0.4318)
			(layers "F.Cu" "F.Mask" "F.Paste")
			(net "M_D_CPU1_SA_CB<4>")
		)
		(pad "AK59" smd circle
			(at 11.380724 -13.337286 270)
			(size 0.4318 0.4318)
			(layers "F.Cu" "F.Mask" "F.Paste")
			(net "M_D_CPU1_SA_CB<1>")
		)
		(pad "AK61" smd circle
			(at 13.008356 -13.337286 270)
			(size 0.4318 0.4318)
			(layers "F.Cu" "F.Mask" "F.Paste")
			(net "GND")
		)
		(pad "AK63" smd circle
			(at 14.635988 -13.337286 270)
			(size 0.4318 0.4318)
			(layers "F.Cu" "F.Mask" "F.Paste")
			(net "M_D_CPU1_SA_DQ<28>")
		)
		(pad "AK65" smd circle
			(at 16.263874 -13.337286 270)
			(size 0.4318 0.4318)
			(layers "F.Cu" "F.Mask" "F.Paste")
			(net "M_D_CPU1_SA_DQ<25>")
		)
		(pad "AK67" smd circle
			(at 17.89176 -13.337286 270)
			(size 0.4318 0.4318)
			(layers "F.Cu" "F.Mask" "F.Paste")
			(net "GND")
		)
		(pad "AK69" smd circle
			(at 19.519392 -13.337286 270)
			(size 0.4318 0.4318)
			(layers "F.Cu" "F.Mask" "F.Paste")
			(net "M_D_CPU1_SA_DQ<20>")
		)
		(pad "AK71" smd circle
			(at 21.147278 -13.337286 270)
			(size 0.4318 0.4318)
			(layers "F.Cu" "F.Mask" "F.Paste")
			(net "M_D_CPU1_SA_DQ<17>")
		)
		(pad "AK73" smd circle
			(at 22.77491 -13.337286 270)
			(size 0.4318 0.4318)
			(layers "F.Cu" "F.Mask" "F.Paste")
			(net "GND")
		)
		(pad "AK75" smd circle
			(at 24.402796 -13.337286 270)
			(size 0.4318 0.4318)
			(layers "F.Cu" "F.Mask" "F.Paste")
			(net "M_D_CPU1_SA_DQ<12>")
		)
		(pad "AK77" smd circle
			(at 26.030682 -13.337286 270)
			(size 0.4318 0.4318)
			(layers "F.Cu" "F.Mask" "F.Paste")
			(net "M_D_CPU1_SA_DQ<9>")
		)
		(pad "AK79" smd circle
			(at 27.658314 -13.337286 270)
			(size 0.4318 0.4318)
			(layers "F.Cu" "F.Mask" "F.Paste")
			(net "GND")
		)
		(pad "AK81" smd circle
			(at 29.2862 -13.337286 270)
			(size 0.4318 0.4318)
			(layers "F.Cu" "F.Mask" "F.Paste")
			(net "GND")
		)
		(pad "AK83" smd circle
			(at 30.914086 -13.337286 270)
			(size 0.4318 0.4318)
			(layers "F.Cu" "F.Mask" "F.Paste")
			(net "GND")
		)
		(pad "AK85" smd circle
			(at 32.541718 -13.337286 270)
			(size 0.4318 0.4318)
			(layers "F.Cu" "F.Mask" "F.Paste")
			(net "P5E_CPU1_PE4_TX_DP<9>")
		)
		(pad "AK87" smd circle
			(at 34.169604 -13.337286 270)
			(size 0.4318 0.4318)
			(layers "F.Cu" "F.Mask" "F.Paste")
			(net "GND")
		)
		(pad "AK89" smd circle
			(at 35.797236 -13.337286 270)
			(size 0.4318 0.4318)
			(layers "F.Cu" "F.Mask" "F.Paste")
			(net "P5E_CPU1_PE4_RX_DN<9>")
		)
		(pad "AK91" smd oval
			(at 37.425122 -13.337286)
			(size 0.381 0.4826)
			(drill
				(offset 0 -0.0508)
			)
			(layers "F.Cu" "F.Mask" "F.Paste")
			(net "GND")
		)
		(pad "AL1" smd oval
			(at -37.425122 -12.977114 180)
			(size 0.381 0.4826)
			(drill
				(offset 0 -0.0508)
			)
			(layers "F.Cu" "F.Mask" "F.Paste")
			(net "GND")
		)
		(pad "AL3" smd circle
			(at -35.797236 -12.977114 270)
			(size 0.4318 0.4318)
			(layers "F.Cu" "F.Mask" "F.Paste")
			(net "UPI_CPU1_CPU0_P0P1_DP<11>")
		)
		(pad "AL5" smd circle
			(at -34.169604 -12.977114 270)
			(size 0.4318 0.4318)
			(layers "F.Cu" "F.Mask" "F.Paste")
			(net "GND")
		)
		(pad "AL7" smd circle
			(at -32.541718 -12.977114 270)
			(size 0.4318 0.4318)
			(layers "F.Cu" "F.Mask" "F.Paste")
			(net "UPI_CPU0_CPU1_P1P0_DP<10>")
		)
		(pad "AL9" smd circle
			(at -30.914086 -12.977114 270)
			(size 0.4318 0.4318)
			(layers "F.Cu" "F.Mask" "F.Paste")
			(net "GND")
		)
		(pad "AL11" smd circle
			(at -29.2862 -12.977114 270)
			(size 0.4318 0.4318)
			(layers "F.Cu" "F.Mask" "F.Paste")
			(net "P5E_CPU1_PE0_RX_DP<10>")
		)
		(pad "AL13" smd circle
			(at -27.658314 -12.977114 270)
			(size 0.4318 0.4318)
			(layers "F.Cu" "F.Mask" "F.Paste")
			(net "GND")
		)
		(pad "AL15" smd circle
			(at -26.030682 -12.977114 270)
			(size 0.4318 0.4318)
			(layers "F.Cu" "F.Mask" "F.Paste")
			(net "P5E_CPU1_PE0_TX_DP<9>")
		)
		(pad "AL17" smd circle
			(at -24.402796 -12.977114 270)
			(size 0.4318 0.4318)
			(layers "F.Cu" "F.Mask" "F.Paste")
			(net "GND")
		)
		(pad "AL19" smd circle
			(at -22.77491 -12.977114 270)
			(size 0.4318 0.4318)
			(layers "F.Cu" "F.Mask" "F.Paste")
			(net "M_D_CPU1_SB_DQ<29>")
		)
		(pad "AL21" smd circle
			(at -21.147278 -12.977114 270)
			(size 0.4318 0.4318)
			(layers "F.Cu" "F.Mask" "F.Paste")
			(net "M_D_CPU1_SB_DQS_DP<3>")
		)
		(pad "AL23" smd circle
			(at -19.519392 -12.977114 270)
			(size 0.4318 0.4318)
			(layers "F.Cu" "F.Mask" "F.Paste")
			(net "M_D_CPU1_SB_DQ<24>")
		)
		(pad "AL25" smd circle
			(at -17.89176 -12.977114 270)
			(size 0.4318 0.4318)
			(layers "F.Cu" "F.Mask" "F.Paste")
			(net "M_D_CPU1_SB_DQ<13>")
		)
		(pad "AL27" smd circle
			(at -16.263874 -12.977114 270)
			(size 0.4318 0.4318)
			(layers "F.Cu" "F.Mask" "F.Paste")
			(net "M_D_CPU1_SB_DQS_DP<1>")
		)
		(pad "AL29" smd circle
			(at -14.635988 -12.977114 270)
			(size 0.4318 0.4318)
			(layers "F.Cu" "F.Mask" "F.Paste")
			(net "M_D_CPU1_SB_DQ<8>")
		)
		(pad "AL31" smd circle
			(at -13.008356 -12.977114 270)
			(size 0.4318 0.4318)
			(layers "F.Cu" "F.Mask" "F.Paste")
			(net "M_D_CPU1_SB_DQ<5>")
		)
		(pad "AL33" smd circle
			(at -11.380724 -12.977114 270)
			(size 0.4318 0.4318)
			(layers "F.Cu" "F.Mask" "F.Paste")
			(net "M_D_CPU1_SB_DQS_DP<0>")
		)
		(pad "AL35" smd circle
			(at -9.752838 -12.977114 270)
			(size 0.4318 0.4318)
			(layers "F.Cu" "F.Mask" "F.Paste")
			(net "M_D_CPU1_SB_DQ<0>")
		)
		(pad "AL37" smd circle
			(at -8.124952 -12.977114 270)
			(size 0.4318 0.4318)
			(layers "F.Cu" "F.Mask" "F.Paste")
			(net "M_D_CPU1_SB_CB<1>")
		)
		(pad "AL39" smd circle
			(at -6.49732 -12.977114 270)
			(size 0.4318 0.4318)
			(layers "F.Cu" "F.Mask" "F.Paste")
			(net "M_D_CPU1_SB_DQS_DP<9>")
		)
		(pad "AL41" smd circle
			(at -4.869434 -12.977114 270)
			(size 0.4318 0.4318)
			(layers "F.Cu" "F.Mask" "F.Paste")
			(net "M_D_CPU1_SB_CB<4>")
		)
		(pad "AL43" smd circle
			(at -3.241802 -12.977114 270)
			(size 0.4318 0.4318)
			(layers "F.Cu" "F.Mask" "F.Paste")
			(net "M_D_CPU1_SB_CA<1>")
		)
		(pad "AL45" smd circle
			(at -1.613916 -12.977114 270)
			(size 0.4318 0.4318)
			(layers "F.Cu" "F.Mask" "F.Paste")
			(net "M_D_CPU1_CLK_DP<0>")
		)
		(pad "AL48" smd circle
			(at 2.427732 -12.867132 270)
			(size 0.4318 0.4318)
			(layers "F.Cu" "F.Mask" "F.Paste")
			(net "M_B_CPU1_SA_RSP<0>")
		)
		(pad "AL50" smd circle
			(at 4.055618 -12.867132 270)
			(size 0.4318 0.4318)
			(layers "F.Cu" "F.Mask" "F.Paste")
			(net "M_D_CPU1_SA_CA<4>")
		)
		(pad "AL52" smd circle
			(at 5.68325 -12.867132 270)
			(size 0.4318 0.4318)
			(layers "F.Cu" "F.Mask" "F.Paste")
			(net "GND")
		)
		(pad "AL54" smd circle
			(at 7.311136 -12.867132 270)
			(size 0.4318 0.4318)
			(layers "F.Cu" "F.Mask" "F.Paste")
			(net "M_D_CPU1_SA_CS_N<0>")
		)
		(pad "AL56" smd circle
			(at 8.939022 -12.867132 270)
			(size 0.4318 0.4318)
			(layers "F.Cu" "F.Mask" "F.Paste")
			(net "M_D_CPU1_SA_CB<5>")
		)
		(pad "AL58" smd circle
			(at 10.566654 -12.867132 270)
			(size 0.4318 0.4318)
			(layers "F.Cu" "F.Mask" "F.Paste")
			(net "M_D_CPU1_SA_DQS_DP<4>")
		)
		(pad "AL60" smd circle
			(at 12.19454 -12.867132 270)
			(size 0.4318 0.4318)
			(layers "F.Cu" "F.Mask" "F.Paste")
			(net "M_D_CPU1_SA_CB<0>")
		)
		(pad "AL62" smd circle
			(at 13.822426 -12.867132 270)
			(size 0.4318 0.4318)
			(layers "F.Cu" "F.Mask" "F.Paste")
			(net "M_D_CPU1_SA_DQ<29>")
		)
		(pad "AL64" smd circle
			(at 15.450058 -12.867132 270)
			(size 0.4318 0.4318)
			(layers "F.Cu" "F.Mask" "F.Paste")
			(net "M_D_CPU1_SA_DQS_DP<3>")
		)
		(pad "AL66" smd circle
			(at 17.07769 -12.867132 270)
			(size 0.4318 0.4318)
			(layers "F.Cu" "F.Mask" "F.Paste")
			(net "M_D_CPU1_SA_DQ<24>")
		)
		(pad "AL68" smd circle
			(at 18.705576 -12.867132 270)
			(size 0.4318 0.4318)
			(layers "F.Cu" "F.Mask" "F.Paste")
			(net "M_D_CPU1_SA_DQ<21>")
		)
		(pad "AL70" smd circle
			(at 20.333462 -12.867132 270)
			(size 0.4318 0.4318)
			(layers "F.Cu" "F.Mask" "F.Paste")
			(net "M_D_CPU1_SA_DQS_DP<2>")
		)
		(pad "AL72" smd circle
			(at 21.961094 -12.867132 270)
			(size 0.4318 0.4318)
			(layers "F.Cu" "F.Mask" "F.Paste")
			(net "M_D_CPU1_SA_DQ<16>")
		)
		(pad "AL74" smd circle
			(at 23.58898 -12.867132 270)
			(size 0.4318 0.4318)
			(layers "F.Cu" "F.Mask" "F.Paste")
			(net "M_D_CPU1_SA_DQ<13>")
		)
		(pad "AL76" smd circle
			(at 25.216612 -12.867132 270)
			(size 0.4318 0.4318)
			(layers "F.Cu" "F.Mask" "F.Paste")
			(net "M_D_CPU1_SA_DQS_DP<1>")
		)
		(pad "AL78" smd circle
			(at 26.844498 -12.867132 270)
			(size 0.4318 0.4318)
			(layers "F.Cu" "F.Mask" "F.Paste")
			(net "M_D_CPU1_SA_DQ<8>")
		)
		(pad "AL80" smd circle
			(at 28.472384 -12.867132 270)
			(size 0.4318 0.4318)
			(layers "F.Cu" "F.Mask" "F.Paste")
			(net "GND")
		)
		(pad "AL82" smd circle
			(at 30.100016 -12.867132 270)
			(size 0.4318 0.4318)
			(layers "F.Cu" "F.Mask" "F.Paste")
			(net "GND")
		)
		(pad "AL84" smd circle
			(at 31.727902 -12.867132 270)
			(size 0.4318 0.4318)
			(layers "F.Cu" "F.Mask" "F.Paste")
			(net "GND")
		)
		(pad "AL86" smd circle
			(at 33.355534 -12.867132 270)
			(size 0.4318 0.4318)
			(layers "F.Cu" "F.Mask" "F.Paste")
			(net "P5E_CPU1_PE4_TX_DN<10>")
		)
		(pad "AL88" smd circle
			(at 34.98342 -12.867132 270)
			(size 0.4318 0.4318)
			(layers "F.Cu" "F.Mask" "F.Paste")
			(net "GND")
		)
		(pad "AL90" smd circle
			(at 36.611306 -12.867132 270)
			(size 0.4318 0.4318)
			(layers "F.Cu" "F.Mask" "F.Paste")
			(net "P5E_CPU1_PE4_RX_DP<10>")
		)
		(pad "AM2" smd circle
			(at -36.611306 -12.507468 270)
			(size 0.4318 0.4318)
			(layers "F.Cu" "F.Mask" "F.Paste")
			(net "UPI_CPU1_CPU0_P0P1_DN<11>")
		)
		(pad "AM4" smd circle
			(at -34.98342 -12.507468 270)
			(size 0.4318 0.4318)
			(layers "F.Cu" "F.Mask" "F.Paste")
			(net "GND")
		)
		(pad "AM6" smd circle
			(at -33.355534 -12.507468 270)
			(size 0.4318 0.4318)
			(layers "F.Cu" "F.Mask" "F.Paste")
			(net "UPI_CPU0_CPU1_P1P0_DP<11>")
		)
		(pad "AM8" smd circle
			(at -31.727902 -12.507468 270)
			(size 0.4318 0.4318)
			(layers "F.Cu" "F.Mask" "F.Paste")
			(net "GND")
		)
		(pad "AM10" smd circle
			(at -30.100016 -12.507468 270)
			(size 0.4318 0.4318)
			(layers "F.Cu" "F.Mask" "F.Paste")
			(net "P5E_CPU1_PE0_RX_DN<11>")
		)
		(pad "AM12" smd circle
			(at -28.472384 -12.507468 270)
			(size 0.4318 0.4318)
			(layers "F.Cu" "F.Mask" "F.Paste")
			(net "GND")
		)
		(pad "AM14" smd circle
			(at -26.844498 -12.507468 270)
			(size 0.4318 0.4318)
			(layers "F.Cu" "F.Mask" "F.Paste")
			(net "P5E_CPU1_PE0_TX_DP<10>")
		)
		(pad "AM16" smd circle
			(at -25.216612 -12.507468 270)
			(size 0.4318 0.4318)
			(layers "F.Cu" "F.Mask" "F.Paste")
			(net "GND")
		)
		(pad "AM18" smd circle
			(at -23.58898 -12.507468 270)
			(size 0.4318 0.4318)
			(layers "F.Cu" "F.Mask" "F.Paste")
			(net "GND")
		)
		(pad "AM20" smd circle
			(at -21.961094 -12.507468 270)
			(size 0.4318 0.4318)
			(layers "F.Cu" "F.Mask" "F.Paste")
			(net "GND")
		)
		(pad "AM22" smd circle
			(at -20.333462 -12.507468 270)
			(size 0.4318 0.4318)
			(layers "F.Cu" "F.Mask" "F.Paste")
			(net "GND")
		)
		(pad "AM24" smd circle
			(at -18.705576 -12.507468 270)
			(size 0.4318 0.4318)
			(layers "F.Cu" "F.Mask" "F.Paste")
			(net "GND")
		)
	)
)
